FILE_TYPE = MACRO_DRAWING;
SET COLOR_WIRE YELLOW;
SET COLOR_PROP ORANGE;
SET COLOR_DOT WHITE;
SET COLOR_ARC YELLOW;
SET COLOR_BODY GREEN;
SET COLOR_NOTE PURPLE;
SET PROP_DISPLAY VALUE;
SET PAGE_NUMBER P9;
FORCEADD QUANTA_TITLE_BLOCK_C..1
(-100 100);
FORCEPROP 1 LAST CUSTOM_TXT_CDS <NAME_2>
J 0
(-3275 150);
FORCEPROP 1 LAST CUSTOM_TXT_CDS <NAME_1>
J 0
(-3275 275);
FORCEPROP 1 LAST CUSTOM_TXT_CDS <Q_NUMBER>
J 0
(-1503 203);
DISPLAY 1.212766 (-1503 203);
FORCEPROP 1 LAST CUSTOM_TXT_CDS <Q_PROJ>
J 0
(-2482 202);
DISPLAY 1.212766 (-2482 202);
FORCEPROP 1 LAST CUSTOM_TXT_CDS <Q_REV>
J 0
(-284 203);
DISPLAY 1.212766 (-284 203);
FORCEPROP 1 LAST CUSTOM_TXT_CDS <CON_LAST_MODIFIED>
J 0
(-1985 115);
DISPLAY 0.978723 (-1985 115);
FORCEPROP 1 LAST CUSTOM_TXT_CDS <CON_PAGE_NUM> OF <CON_TOTAL_PAGES>
J 0
(-546 118);
DISPLAY 0.978723 (-546 118);
FORCEPROP 1 LAST Q_TITLE BLOCK DIAGRAM - POWER SEQUENCE
J 0
(-9375 150);
DISPLAY 2.446809 (-9375 150);
PAINT GREEN (-9375 150);
FORCEPROP 2 LAST PAGE_BORDER TRUE
J 0
(-7990 5350);
DISPLAY 0.638298 (-7990 5350);
PAINT PINK (-7990 5350);
DISPLAY INVISIBLE (-7990 5350);
FORCEPROP 1 LAST CDS_LMAN_SYM_OUTLINE -9475,6775,100,-125
J 0
(-100 100);
DISPLAY 0.468085 (-100 100);
PAINT GREEN (-100 100);
DISPLAY INVISIBLE (-100 100);
FORCEPROP 2 LAST CDS_LIB pure_quanta
J 0
(-100 100);
DISPLAY INVISIBLE (-100 100);
FORCEPROP 2 LAST CDS_XR_PAGE_TITLE CR-9 : @T6G_MB_LIB.T6G(SCH_1):PAGE9
J 0
(-7990 5350);
DISPLAY 0.638298 (-7990 5350);
PAINT PINK (-7990 5350);
DISPLAY INVISIBLE (-7990 5350);
FORCEPROP 2 LAST CUSTOM_TXT_CDS <XR_PAGE_TITLE>
J 0
(-7990 5350);
DISPLAY 0.638298 (-7990 5350);
PAINT PINK (-7990 5350);
DISPLAY INVISIBLE (-7990 5350);
FORCEPROP 1 LAST COMMENT_BODY TRUE
J 0
(-88 87);
DISPLAY 0.978723 (-88 87);
PAINT GREEN (-88 87);
DISPLAY INVISIBLE (-88 87);
FORCEPROP 1 LAST Q_DEPT BU9
J 1
(-3863 149);
DISPLAY 1.957447 (-3863 149);
PAINT GREEN (-3863 149);
DISPLAY INVISIBLE (-3863 149);
FORCEPROP 0 LAST CDS_CON_LAST_MODIFIED Thu Aug 24 10:13:30 2023
J 0
(-1985 115);
DISPLAY INVISIBLE (-1985 115);
FORCENOTE
$CDS_IMAGE|clipboard_0_28.jpg|4083|4216
(-7225 3650) 0;
DISPLAY LEFT (-7225 3650);
FORCENOTE
$CDS_IMAGE|clipboard_1_17.jpg|4066|4577
(-2575 3625) 0;
DISPLAY LEFT (-2575 3625);
QUIT
